(kicad_pcb
	(version 20241229)
	(generator "pcbnew")
	(generator_version "9.0")
	(general
		(thickness 1.599998)
		(legacy_teardrops no)
	)
	(paper "A4")
	(title_block
		(title "Artix - Datacenter Secure Control Module (DC-SCM)")
		(date "2024-11-06")
		(rev "1.1.3")
		(comment 9 "footprints 159-163 of 544")
	)
	(layers
		(0 "F.Cu" signal)
		(4 "In1.Cu" signal)
		(6 "In2.Cu" signal)
		(8 "In3.Cu" signal)
		(10 "In4.Cu" signal)
		(12 "In5.Cu" signal)
		(14 "In6.Cu" signal)
		(2 "B.Cu" signal)
		(9 "F.Adhes" user "F.Adhesive")
		(11 "B.Adhes" user "B.Adhesive")
		(13 "F.Paste" user)
		(15 "B.Paste" user)
		(5 "F.SilkS" user "F.Silkscreen")
		(7 "B.SilkS" user "B.Silkscreen")
		(1 "F.Mask" user)
		(3 "B.Mask" user)
		(17 "Dwgs.User" user "User.Drawings")
		(19 "Cmts.User" user "User.Comments")
		(21 "Eco1.User" user "User.Eco1")
		(23 "Eco2.User" user "User.Eco2")
		(25 "Edge.Cuts" user)
		(27 "Margin" user)
		(31 "F.CrtYd" user "F.Courtyard")
		(29 "B.CrtYd" user "B.Courtyard")
		(35 "F.Fab" user)
		(33 "B.Fab" user)
	)
	(footprint "antmicro-footprints:R_0402_1005Metric"
		(layer "F.Cu")
		(at 81.19 123.645 -90)
		(descr "Resistor SMD 0402")
		(tags "resistor SMD 0402")
		(property "Reference" "R145"
			(at 0.855 -0.31 90)
			(layer "F.SilkS")
			(effects
				(font
					(size 0.7 0.7)
					(thickness 0.15)
				)
				(justify right bottom)
			)
		)
		(property "Value" "R_0R_0402"
			(at 0 1.4 90)
			(layer "F.Fab")
			(effects
				(font
					(size 0.7 0.7)
					(thickness 0.15)
				)
				(justify right bottom)
			)
		)
		(property "Datasheet" "https://industrial.panasonic.com/cdbs/www-data/pdf/RDA0000/AOA0000C301.pdf"
			(at 0 0 270)
			(layer "F.Fab")
			(hide yes)
			(effects
				(font
					(size 1.27 1.27)
					(thickness 0.15)
				)
			)
		)
		(property "Description" "SMD Chip Resistor, Jumper, 0 ohm, 100 mW, 0402 [1005 Metric], Thick Film, General Purpose"
			(at 0 0 270)
			(layer "F.Fab")
			(hide yes)
			(effects
				(font
					(size 1.27 1.27)
					(thickness 0.15)
				)
			)
		)
		(property "Author" "Antmicro"
			(at -42.455 204.835 0)
			(layer "F.Fab")
			(hide yes)
			(effects
				(font
					(size 1 1)
					(thickness 0.15)
				)
			)
		)
		(property "Current" "1A"
			(at -42.455 204.835 0)
			(layer "F.Fab")
			(hide yes)
			(effects
				(font
					(size 1 1)
					(thickness 0.15)
				)
			)
		)
		(property "License" "Apache-2.0"
			(at -42.455 204.835 0)
			(layer "F.Fab")
			(hide yes)
			(effects
				(font
					(size 1 1)
					(thickness 0.15)
				)
			)
		)
		(property "MPN" "ERJ2GE0R00X"
			(at -42.455 204.835 0)
			(layer "F.Fab")
			(hide yes)
			(effects
				(font
					(size 1 1)
					(thickness 0.15)
				)
			)
		)
		(property "Manufacturer" "Panasonic"
			(at -42.455 204.835 0)
			(layer "F.Fab")
			(hide yes)
			(effects
				(font
					(size 1 1)
					(thickness 0.15)
				)
			)
		)
		(property "Tolerance" "~"
			(at -42.455 204.835 0)
			(layer "F.Fab")
			(hide yes)
			(effects
				(font
					(size 1 1)
					(thickness 0.15)
				)
			)
		)
		(property "Val" "0R"
			(at -42.455 204.835 0)
			(layer "F.Fab")
			(hide yes)
			(effects
				(font
					(size 1 1)
					(thickness 0.15)
				)
			)
		)
		(sheetname "/Edge connector/")
		(sheetfile "edge-connector.kicad_sch")
		(attr smd)
		(fp_rect
			(start -0.925 -0.47)
			(end 0.925 0.47)
			(stroke
				(width 0.05)
				(type default)
			)
			(fill no)
			(layer "F.CrtYd")
		)
		(fp_rect
			(start -0.5 -0.25)
			(end 0.5 0.25)
			(stroke
				(width 0.15)
				(type solid)
			)
			(fill no)
			(layer "F.Fab")
		)
		(pad "1" smd roundrect
			(at -0.48 0 270)
			(size 0.59 0.64)
			(layers "F.Cu" "F.Mask" "F.Paste")
			(roundrect_rratio 0.25)
			(net 524 "SPI0_CLK_R")
			(pintype "passive")
		)
		(pad "2" smd roundrect
			(at 0.48 0 270)
			(size 0.59 0.64)
			(layers "F.Cu" "F.Mask" "F.Paste")
			(roundrect_rratio 0.25)
			(net 56 "SPI0_CLK")
			(pintype "passive")
		)
	)
	(footprint "antmicro-footprints:R_0603_1608Metric"
		(layer "F.Cu")
		(at 79.925 72.1 90)
		(descr "Resistor SMD 0603")
		(tags "resistor SMD 0603")
		(property "Reference" "R188"
			(at -0.3 -16.514 90)
			(layer "F.SilkS")
			(effects
				(font
					(size 0.7 0.7)
					(thickness 0.15)
				)
				(justify left bottom)
			)
		)
		(property "Value" "R_0R_0603"
			(at 0 1.6 90)
			(layer "F.Fab")
			(effects
				(font
					(size 0.7 0.7)
					(thickness 0.15)
				)
				(justify left bottom)
			)
		)
		(property "Datasheet" "https://www.bourns.com/docs/product-datasheets/cr.pdf?sfvrsn=574d41f6_14"
			(at 0 0 90)
			(layer "F.Fab")
			(hide yes)
			(effects
				(font
					(size 1.27 1.27)
					(thickness 0.15)
				)
			)
		)
		(property "Description" "Zero Ohm Resistor, Jumper, 0603 [1608 Metric], Thick Film, 100 mW, 1 A, Surface Mount Device, CR"
			(at 0 0 90)
			(layer "F.Fab")
			(hide yes)
			(effects
				(font
					(size 1.27 1.27)
					(thickness 0.15)
				)
			)
		)
		(property "Author" "Antmicro"
			(at 152.025 -7.825 0)
			(layer "F.Fab")
			(hide yes)
			(effects
				(font
					(size 1 1)
					(thickness 0.15)
				)
			)
		)
		(property "Current" "1A"
			(at 152.025 -7.825 0)
			(layer "F.Fab")
			(hide yes)
			(effects
				(font
					(size 1 1)
					(thickness 0.15)
				)
			)
		)
		(property "License" "Apache-2.0"
			(at 152.025 -7.825 0)
			(layer "F.Fab")
			(hide yes)
			(effects
				(font
					(size 1 1)
					(thickness 0.15)
				)
			)
		)
		(property "MPN" "CR0603-J/-000ELF"
			(at 152.025 -7.825 0)
			(layer "F.Fab")
			(hide yes)
			(effects
				(font
					(size 1 1)
					(thickness 0.15)
				)
			)
		)
		(property "Manufacturer" "Bourns"
			(at 152.025 -7.825 0)
			(layer "F.Fab")
			(hide yes)
			(effects
				(font
					(size 1 1)
					(thickness 0.15)
				)
			)
		)
		(property "Tolerance" "~"
			(at 152.025 -7.825 0)
			(layer "F.Fab")
			(hide yes)
			(effects
				(font
					(size 1 1)
					(thickness 0.15)
				)
			)
		)
		(property "Val" "0R"
			(at 152.025 -7.825 0)
			(layer "F.Fab")
			(hide yes)
			(effects
				(font
					(size 1 1)
					(thickness 0.15)
				)
			)
		)
		(sheetname "/Power supply/")
		(sheetfile "power-supply.kicad_sch")
		(attr smd)
		(fp_line
			(start -0.15 -0.4)
			(end 0.15 -0.4)
			(stroke
				(width 0.15)
				(type solid)
			)
			(layer "F.SilkS")
		)
		(fp_line
			(start -0.15 0.4)
			(end 0.15 0.4)
			(stroke
				(width 0.15)
				(type solid)
			)
			(layer "F.SilkS")
		)
		(fp_rect
			(start -1.25 -0.65)
			(end 1.25 0.65)
			(stroke
				(width 0.05)
				(type solid)
			)
			(fill no)
			(layer "F.CrtYd")
		)
		(fp_rect
			(start -0.8 -0.4)
			(end 0.8 0.4)
			(stroke
				(width 0.15)
				(type solid)
			)
			(fill no)
			(layer "F.Fab")
		)
		(pad "1" smd roundrect
			(at -0.7 0 90)
			(size 0.8 1)
			(layers "F.Cu" "F.Mask" "F.Paste")
			(roundrect_rratio 0.2)
			(net 339 "VCC1V2")
			(pintype "passive")
		)
		(pad "2" smd roundrect
			(at 0.7 0 90)
			(size 0.8 1)
			(layers "F.Cu" "F.Mask" "F.Paste")
			(roundrect_rratio 0.2)
			(net 60 "Net-(C101-Pad2)")
			(pintype "passive")
		)
	)
	(footprint "antmicro-footprints:QFN-8_2x1.5mm"
		(layer "F.Cu")
		(at 86.975 74.6 180)
		(property "Reference" "U16"
			(at 0.425 1.21 180)
			(layer "F.SilkS")
			(effects
				(font
					(size 0.7 0.7)
					(thickness 0.15)
				)
				(justify left bottom)
			)
		)
		(property "Value" "TPS62823DLCT"
			(at 0 2.2 180)
			(layer "F.Fab")
			(effects
				(font
					(size 0.7 0.7)
					(thickness 0.15)
				)
				(justify left bottom)
			)
		)
		(property "Datasheet" "https://www.ti.com/lit/ds/symlink/tps62823.pdf?ts=1685970309606&ref_url=https%253A%252F%252Fwww.ti.com%252Fproduct%252FTPS62823%252Fpart-details%252FTPS62823DLCT"
			(at 0 0 180)
			(layer "F.Fab")
			(hide yes)
			(effects
				(font
					(size 1.27 1.27)
					(thickness 0.15)
				)
			)
		)
		(property "Description" "DC/DC converter"
			(at 0 0 180)
			(layer "F.Fab")
			(hide yes)
			(effects
				(font
					(size 1.27 1.27)
					(thickness 0.15)
				)
			)
		)
		(property "Author" "Antmicro"
			(at 173.95 149.2 0)
			(layer "F.Fab")
			(hide yes)
			(effects
				(font
					(size 1 1)
					(thickness 0.15)
				)
			)
		)
		(property "License" "Apache-2.0"
			(at 173.95 149.2 0)
			(layer "F.Fab")
			(hide yes)
			(effects
				(font
					(size 1 1)
					(thickness 0.15)
				)
			)
		)
		(property "MPN" "TPS62823DLCT"
			(at 173.95 149.2 0)
			(layer "F.Fab")
			(hide yes)
			(effects
				(font
					(size 1 1)
					(thickness 0.15)
				)
			)
		)
		(property "Manufacturer" "Texas Instruments"
			(at 173.95 149.2 0)
			(layer "F.Fab")
			(hide yes)
			(effects
				(font
					(size 1 1)
					(thickness 0.15)
				)
			)
		)
		(sheetname "/Power supply/")
		(sheetfile "power-supply.kicad_sch")
		(attr smd)
		(fp_line
			(start -0.25 -1.05)
			(end 0.9 -1.05)
			(stroke
				(width 0.15)
				(type solid)
			)
			(layer "F.SilkS")
		)
		(fp_line
			(start -0.9 1.05)
			(end 0.9 1.05)
			(stroke
				(width 0.15)
				(type solid)
			)
			(layer "F.SilkS")
		)
		(fp_circle
			(center -0.9 -1.05)
			(end -0.849 -1.05)
			(stroke
				(width 0.15)
				(type solid)
			)
			(fill yes)
			(layer "F.SilkS")
		)
		(fp_rect
			(start -1.1 -1.25)
			(end 1.1 1.25)
			(stroke
				(width 0.05)
				(type solid)
			)
			(fill no)
			(layer "F.CrtYd")
		)
		(fp_line
			(start 0.998 0.998)
			(end -1 0.998)
			(stroke
				(width 0.15)
				(type solid)
			)
			(layer "F.Fab")
		)
		(fp_line
			(start 0.998 -1)
			(end 0.998 0.998)
			(stroke
				(width 0.15)
				(type solid)
			)
			(layer "F.Fab")
		)
		(fp_line
			(start -0.5 -1)
			(end 0.998 -1)
			(stroke
				(width 0.15)
				(type solid)
			)
			(layer "F.Fab")
		)
		(fp_line
			(start -1 0.998)
			(end -1 -0.5)
			(stroke
				(width 0.15)
				(type solid)
			)
			(layer "F.Fab")
		)
		(fp_line
			(start -1 -0.5)
			(end -0.5 -1)
			(stroke
				(width 0.15)
				(type solid)
			)
			(layer "F.Fab")
		)
		(pad "1" smd rect
			(at -0.677 -0.75 180)
			(size 0.55 0.25)
			(layers "F.Cu" "F.Mask" "F.Paste")
			(net 347 "Net-(U16-EN)")
			(pinfunction "EN")
			(pintype "input")
		)
		(pad "2" smd rect
			(at -0.677 -0.25 180)
			(size 0.55 0.25)
			(layers "F.Cu" "F.Mask" "F.Paste")
			(net 10 "Net-(U16-FB)")
			(pinfunction "FB")
			(pintype "bidirectional")
		)
		(pad "3" smd rect
			(at -0.677 0.248 180)
			(size 0.55 0.25)
			(layers "F.Cu" "F.Mask" "F.Paste")
			(net 1 "GND")
			(pinfunction "AGND")
			(pintype "power_in")
		)
		(pad "4" smd rect
			(at -0.677 0.748 180)
			(size 0.55 0.25)
			(layers "F.Cu" "F.Mask" "F.Paste")
			(net 646 "unconnected-(U16-NC-Pad4)")
			(pinfunction "NC")
			(pintype "no_connect")
		)
		(pad "5" smd rect
			(at 0.675 0.748 180)
			(size 0.55 0.25)
			(layers "F.Cu" "F.Mask" "F.Paste")
			(net 1 "GND")
			(pinfunction "PGND")
			(pintype "power_in")
		)
		(pad "6" smd rect
			(at 0.675 0.248 180)
			(size 0.55 0.25)
			(layers "F.Cu" "F.Mask" "F.Paste")
			(net 291 "Net-(U16-SW)")
			(pinfunction "SW")
			(pintype "bidirectional")
		)
		(pad "7" smd rect
			(at 0.675 -0.25 180)
			(size 0.55 0.25)
			(layers "F.Cu" "F.Mask" "F.Paste")
			(net 4 "VCC5V0")
			(pinfunction "VIN")
			(pintype "power_in")
		)
		(pad "8" smd rect
			(at 0.675 -0.75 180)
			(size 0.55 0.25)
			(layers "F.Cu" "F.Mask" "F.Paste")
			(net 534 "/Power supply/1V2_PG")
			(pinfunction "PG")
			(pintype "output")
		)
	)
	(footprint "antmicro-footprints:L_Vishay-IHLP-1212AE"
		(layer "F.Cu")
		(at 82.5 72.4 90)
		(property "Reference" "L6"
			(at 1.8285 -17.25 90)
			(layer "F.SilkS")
			(effects
				(font
					(size 0.7 0.7)
					(thickness 0.15)
				)
				(justify left bottom)
			)
		)
		(property "Value" "L_470n_6.7A_Vishay-IHLP-1212AE-11"
			(at 1.278 3.401 90)
			(layer "F.Fab")
			(effects
				(font
					(size 0.7 0.7)
					(thickness 0.15)
				)
				(justify left bottom)
			)
		)
		(property "Datasheet" "https://www.vishay.com/docs/34300/ihlp-1212ae-11.pdf"
			(at 0 0 90)
			(layer "F.Fab")
			(hide yes)
			(effects
				(font
					(size 1.27 1.27)
					(thickness 0.15)
				)
			)
		)
		(property "Description" "Power Inductor (SMT), 470 nH, 6.7 A, Shielded, 6.7 A"
			(at 0 0 90)
			(layer "F.Fab")
			(hide yes)
			(effects
				(font
					(size 1.27 1.27)
					(thickness 0.15)
				)
			)
		)
		(property "Author" "Antmicro"
			(at 154.9 -10.1 0)
			(layer "F.Fab")
			(hide yes)
			(effects
				(font
					(size 1 1)
					(thickness 0.15)
				)
			)
		)
		(property "IMax" "6.7 A"
			(at 154.9 -10.1 0)
			(layer "F.Fab")
			(hide yes)
			(effects
				(font
					(size 1 1)
					(thickness 0.15)
				)
			)
		)
		(property "ISat" "6.7 A"
			(at 154.9 -10.1 0)
			(layer "F.Fab")
			(hide yes)
			(effects
				(font
					(size 1 1)
					(thickness 0.15)
				)
			)
		)
		(property "License" "Apache-2.0"
			(at 154.9 -10.1 0)
			(layer "F.Fab")
			(hide yes)
			(effects
				(font
					(size 1 1)
					(thickness 0.15)
				)
			)
		)
		(property "MPN" "IHLP1212AEERR47M11"
			(at 154.9 -10.1 0)
			(layer "F.Fab")
			(hide yes)
			(effects
				(font
					(size 1 1)
					(thickness 0.15)
				)
			)
		)
		(property "Manufacturer" "Vishay"
			(at 154.9 -10.1 0)
			(layer "F.Fab")
			(hide yes)
			(effects
				(font
					(size 1 1)
					(thickness 0.15)
				)
			)
		)
		(property "Size" "3.0x3.0"
			(at 154.9 -10.1 0)
			(layer "F.Fab")
			(hide yes)
			(effects
				(font
					(size 1 1)
					(thickness 0.15)
				)
			)
		)
		(property "Val" "470n/6.7A"
			(at 154.9 -10.1 0)
			(layer "F.Fab")
			(hide yes)
			(effects
				(font
					(size 1 1)
					(thickness 0.15)
				)
			)
		)
		(sheetname "/Power supply/")
		(sheetfile "power-supply.kicad_sch")
		(attr smd)
		(fp_line
			(start 1.653 -1.6)
			(end 1.653 -0.9)
			(stroke
				(width 0.15)
				(type solid)
			)
			(layer "F.SilkS")
		)
		(fp_line
			(start -1.647 -1.6)
			(end 1.653 -1.6)
			(stroke
				(width 0.15)
				(type solid)
			)
			(layer "F.SilkS")
		)
		(fp_line
			(start -1.647 -0.9)
			(end -1.647 -1.6)
			(stroke
				(width 0.15)
				(type solid)
			)
			(layer "F.SilkS")
		)
		(fp_line
			(start 1.653 0.9)
			(end 1.653 1.601)
			(stroke
				(width 0.15)
				(type solid)
			)
			(layer "F.SilkS")
		)
		(fp_line
			(start -1.647 1.6)
			(end -1.647 0.9)
			(stroke
				(width 0.15)
				(type solid)
			)
			(layer "F.SilkS")
		)
		(fp_line
			(start 1.653 1.601)
			(end -1.647 1.6)
			(stroke
				(width 0.15)
				(type solid)
			)
			(layer "F.SilkS")
		)
		(fp_rect
			(start -2.35 -1.85)
			(end 2.35 1.85)
			(stroke
				(width 0.05)
				(type solid)
			)
			(fill no)
			(layer "F.CrtYd")
		)
		(fp_rect
			(start -1.803 -1.601)
			(end 1.803 1.601)
			(stroke
				(width 0.15)
				(type solid)
			)
			(fill no)
			(layer "F.Fab")
		)
		(pad "1" smd roundrect
			(at -1.35 0 90)
			(size 1.5 1.2)
			(layers "F.Cu" "F.Mask" "F.Paste")
			(roundrect_rratio 0.1)
			(net 291 "Net-(U16-SW)")
			(pintype "passive")
		)
		(pad "2" smd roundrect
			(at 1.35 0 90)
			(size 1.5 1.2)
			(layers "F.Cu" "F.Mask" "F.Paste")
			(roundrect_rratio 0.1)
			(net 60 "Net-(C101-Pad2)")
			(pintype "passive")
		)
	)
	(footprint "antmicro-footprints:R_0402_1005Metric"
		(layer "F.Cu")
		(at 89.52 74.4 90)
		(descr "Resistor SMD 0402")
		(tags "resistor SMD 0402")
		(property "Reference" "R187"
			(at -1 3.38 90)
			(layer "F.SilkS")
			(effects
				(font
					(size 0.7 0.7)
					(thickness 0.15)
				)
				(justify left bottom)
			)
		)
		(property "Value" "R_100k_0402"
			(at 0 1.4 90)
			(layer "F.Fab")
			(effects
				(font
					(size 0.7 0.7)
					(thickness 0.15)
				)
				(justify left bottom)
			)
		)
		(property "Datasheet" "https://www.bourns.com/docs/product-datasheets/cr.pdf"
			(at 0 0 90)
			(layer "F.Fab")
			(hide yes)
			(effects
				(font
					(size 1.27 1.27)
					(thickness 0.15)
				)
			)
		)
		(property "Description" "SMD Chip Resistor, 100 kohm, ± 1%, 62.5 mW, 0402 [1005 Metric], Thick Film, General Purpose"
			(at 0 0 90)
			(layer "F.Fab")
			(hide yes)
			(effects
				(font
					(size 1.27 1.27)
					(thickness 0.15)
				)
			)
		)
		(property "Author" "Antmicro"
			(at 163.92 -15.12 0)
			(layer "F.Fab")
			(hide yes)
			(effects
				(font
					(size 1 1)
					(thickness 0.15)
				)
			)
		)
		(property "License" "Apache-2.0"
			(at 163.92 -15.12 0)
			(layer "F.Fab")
			(hide yes)
			(effects
				(font
					(size 1 1)
					(thickness 0.15)
				)
			)
		)
		(property "MPN" "CR0402-FX-1003GLF"
			(at 163.92 -15.12 0)
			(layer "F.Fab")
			(hide yes)
			(effects
				(font
					(size 1 1)
					(thickness 0.15)
				)
			)
		)
		(property "Manufacturer" "Bourns"
			(at 163.92 -15.12 0)
			(layer "F.Fab")
			(hide yes)
			(effects
				(font
					(size 1 1)
					(thickness 0.15)
				)
			)
		)
		(property "Tolerance" "1%"
			(at 163.92 -15.12 0)
			(layer "F.Fab")
			(hide yes)
			(effects
				(font
					(size 1 1)
					(thickness 0.15)
				)
			)
		)
		(property "Val" "100k"
			(at 163.92 -15.12 0)
			(layer "F.Fab")
			(hide yes)
			(effects
				(font
					(size 1 1)
					(thickness 0.15)
				)
			)
		)
		(sheetname "/Power supply/")
		(sheetfile "power-supply.kicad_sch")
		(attr smd)
		(fp_rect
			(start -0.925 -0.47)
			(end 0.925 0.47)
			(stroke
				(width 0.05)
				(type default)
			)
			(fill no)
			(layer "F.CrtYd")
		)
		(fp_rect
			(start -0.5 -0.25)
			(end 0.5 0.25)
			(stroke
				(width 0.15)
				(type solid)
			)
			(fill no)
			(layer "F.Fab")
		)
		(pad "1" smd roundrect
			(at -0.48 0 90)
			(size 0.59 0.64)
			(layers "F.Cu" "F.Mask" "F.Paste")
			(roundrect_rratio 0.25)
			(net 10 "Net-(U16-FB)")
			(pintype "passive")
		)
		(pad "2" smd roundrect
			(at 0.48 0 90)
			(size 0.59 0.64)
			(layers "F.Cu" "F.Mask" "F.Paste")
			(roundrect_rratio 0.25)
			(net 1 "GND")
			(pintype "passive")
		)
	)
)
